(kicad_pcb
	(version 20260206)
	(generator "pcbnew")
	(generator_version "10.0")
	(general
		(thickness 1.6)
		(legacy_teardrops no)
	)
	(paper "A4")
	(title_block
		(title "baseboard — 13948-1b.1110WZS1818.brd")
		(comment 1 "Honey Badger (Wiwynn) / footprints 938-943 of 2523")
	)
	(layers
		(0 "F.Cu" signal "TOP")
		(4 "In1.Cu" signal "L2GND")
		(6 "In2.Cu" signal "L3")
		(8 "In3.Cu" signal "L4VCC")
		(10 "In4.Cu" signal "L5VCC")
		(12 "In5.Cu" signal "L6")
		(14 "In6.Cu" signal "L7GND")
		(2 "B.Cu" signal "BOTTOM")
		(9 "F.Adhes" user "F.Adhesive")
		(11 "B.Adhes" user "B.Adhesive")
		(13 "F.Paste" user "Package Geometry/Pastemask Top")
		(15 "B.Paste" user "Package Geometry/Pastemask Bottom")
		(5 "F.SilkS" user "Ref Des/Silkscreen Top")
		(7 "B.SilkS" user "Ref Des/Silkscreen Bottom")
		(1 "F.Mask" user "Board Geometry/Soldermask Top")
		(3 "B.Mask" user "Board Geometry/Soldermask Bottom")
		(17 "Dwgs.User" user "User.Drawings")
		(19 "Cmts.User" user "User.Comments")
		(21 "Eco1.User" user "User.Eco1")
		(23 "Eco2.User" user "User.Eco2")
		(25 "Edge.Cuts" user "Board Geometry/Outline")
		(27 "Margin" user)
		(31 "F.CrtYd" user "Package Geometry/Place Bound Top")
		(29 "B.CrtYd" user "Package Geometry/Place Bound Bottom")
		(35 "F.Fab" user "Ref Des/Assembly Top")
		(33 "B.Fab" user "Ref Des/Assembly Bottom")
	)
	(footprint ""
		(layer "F.Cu")
		(at 131.318 -91.948 90)
		(property "Reference" "SC1105"
			(at 0 0 90)
			(layer "F.SilkS")
			(hide yes)
			(effects
				(font
					(size 1.27 1.27)
				)
			)
		)
		(property "Value" "SCD01U10V1KX-GP"
			(at -2.8321 -1.7399 90)
			(unlocked yes)
			(layer "F.Fab")
			(hide yes)
			(effects
				(font
					(size 1.016 1.016)
					(thickness 0.1524)
				)
			)
		)
		(property "Device Type" "C0201H13"
			(at -2.8321 -3.2639 90)
			(unlocked yes)
			(layer "F.Fab")
			(hide yes)
			(effects
				(font
					(size 1.016 1.016)
					(thickness 0.1524)
				)
			)
		)
		(duplicate_pad_numbers_are_jumpers no)
		(fp_rect
			(start -0.2794 0.6477)
			(end 0.2794 -0.6477)
			(stroke
				(width 0)
				(type default)
			)
			(fill no)
			(layer "F.CrtYd")
		)
		(fp_rect
			(start -0.2794 0.6477)
			(end 0.2794 -0.6477)
			(stroke
				(width 0)
				(type default)
			)
			(fill no)
			(layer "F.Fab")
		)
		(pad "1" smd custom
			(at 0 -0.2794 90)
			(size 0.0762 0.0762)
			(layers "F.Cu" "F.Mask" "F.Paste")
			(net "3X24_SAS_TX19_N")
			(options
				(clearance outline)
				(anchor circle)
			)
			(primitives
				(gr_poly
					(pts
						(arc
							(start 0.1524 -0.127)
							(mid 0.137521 -0.162921)
							(end 0.1016 -0.1778)
						)
						(arc
							(start -0.1016 -0.1778)
							(mid -0.137521 -0.162921)
							(end -0.1524 -0.127)
						)
						(arc
							(start -0.1524 0.127)
							(mid -0.137521 0.162921)
							(end -0.1016 0.1778)
						)
						(arc
							(start 0.1016 0.1778)
							(mid 0.137521 0.162921)
							(end 0.1524 0.127)
						)
					)
					(width 0)
					(fill yes)
				)
			)
		)
		(pad "2" smd custom
			(at 0 0.2794 90)
			(size 0.0762 0.0762)
			(layers "F.Cu" "F.Mask" "F.Paste")
			(net "SAS_EXP2CONN_TX_N_23")
			(options
				(clearance outline)
				(anchor circle)
			)
			(primitives
				(gr_poly
					(pts
						(arc
							(start 0.1524 -0.127)
							(mid 0.137521 -0.162921)
							(end 0.1016 -0.1778)
						)
						(arc
							(start -0.1016 -0.1778)
							(mid -0.137521 -0.162921)
							(end -0.1524 -0.127)
						)
						(arc
							(start -0.1524 0.127)
							(mid -0.137521 0.162921)
							(end -0.1016 0.1778)
						)
						(arc
							(start 0.1016 0.1778)
							(mid 0.137521 0.162921)
							(end 0.1524 0.127)
						)
					)
					(width 0)
					(fill yes)
				)
			)
		)
	)
	(footprint ""
		(layer "F.Cu")
		(at 205.74 -185.42 180)
		(property "Reference" "R485"
			(at 0 0 180)
			(layer "F.SilkS")
			(hide yes)
			(effects
				(font
					(size 1.27 1.27)
				)
			)
		)
		(property "Value" "1KR2F-3-GP"
			(at 0.064008 -3.993896 180)
			(unlocked yes)
			(layer "F.Fab")
			(hide yes)
			(effects
				(font
					(size 1.016 1.016)
					(thickness 0.1524)
				)
			)
		)
		(property "Device Type" "R402H16"
			(at 0.064008 -5.517896 180)
			(unlocked yes)
			(layer "F.Fab")
			(hide yes)
			(effects
				(font
					(size 1.016 1.016)
					(thickness 0.1524)
				)
			)
		)
		(duplicate_pad_numbers_are_jumpers no)
		(fp_line
			(start 0.508 -0.9398)
			(end -0.508 -0.9398)
			(stroke
				(width 0.1524)
				(type default)
			)
			(layer "F.SilkS")
		)
		(fp_line
			(start -0.508 -0.9398)
			(end -0.508 0.9398)
			(stroke
				(width 0.1524)
				(type default)
			)
			(layer "F.SilkS")
		)
		(fp_rect
			(start -0.508 0.9398)
			(end 0.508 -0.9398)
			(stroke
				(width 0)
				(type default)
			)
			(fill no)
			(layer "F.CrtYd")
		)
		(fp_rect
			(start -0.508 0.9398)
			(end 0.508 -0.9398)
			(stroke
				(width 0)
				(type default)
			)
			(fill no)
			(layer "F.Fab")
		)
		(pad "1" smd custom
			(at 0 -0.4445 180)
			(size 0.1397 0.1397)
			(layers "F.Cu" "F.Mask" "F.Paste")
			(net "DIVIDER 2_IN")
			(options
				(clearance outline)
				(anchor circle)
			)
			(primitives
				(gr_poly
					(pts
						(arc
							(start -0.1778 -0.2794)
							(mid -0.249642 -0.249642)
							(end -0.2794 -0.1778)
						)
						(arc
							(start -0.2794 0.1778)
							(mid -0.249642 0.249642)
							(end -0.1778 0.2794)
						)
						(arc
							(start 0.1778 0.2794)
							(mid 0.249642 0.249642)
							(end 0.2794 0.1778)
						)
						(arc
							(start 0.2794 -0.1778)
							(mid 0.249642 -0.249642)
							(end 0.1778 -0.2794)
						)
					)
					(width 0)
					(fill yes)
				)
			)
		)
		(pad "2" smd custom
			(at 0 0.4445 180)
			(size 0.1397 0.1397)
			(layers "F.Cu" "F.Mask" "F.Paste")
			(net "GND")
			(options
				(clearance outline)
				(anchor circle)
			)
			(primitives
				(gr_poly
					(pts
						(arc
							(start -0.1778 -0.2794)
							(mid -0.249642 -0.249642)
							(end -0.2794 -0.1778)
						)
						(arc
							(start -0.2794 0.1778)
							(mid -0.249642 0.249642)
							(end -0.1778 0.2794)
						)
						(arc
							(start 0.1778 0.2794)
							(mid 0.249642 0.249642)
							(end 0.2794 0.1778)
						)
						(arc
							(start 0.2794 -0.1778)
							(mid 0.249642 -0.249642)
							(end 0.1778 -0.2794)
						)
					)
					(width 0)
					(fill yes)
				)
			)
		)
	)
	(footprint ""
		(layer "F.Cu")
		(at 333.912718 -157.838648 90)
		(property "Reference" "R216"
			(at 0 0 90)
			(layer "F.SilkS")
			(hide yes)
			(effects
				(font
					(size 1.27 1.27)
				)
			)
		)
		(property "Value" "4K7R2F-GP"
			(at 0.064008 -3.993896 90)
			(unlocked yes)
			(layer "F.Fab")
			(hide yes)
			(effects
				(font
					(size 1.016 1.016)
					(thickness 0.1524)
				)
			)
		)
		(property "Device Type" "R402H16"
			(at 0.064008 -5.517896 90)
			(unlocked yes)
			(layer "F.Fab")
			(hide yes)
			(effects
				(font
					(size 1.016 1.016)
					(thickness 0.1524)
				)
			)
		)
		(duplicate_pad_numbers_are_jumpers no)
		(fp_line
			(start 0.508 -0.9398)
			(end -0.508 -0.9398)
			(stroke
				(width 0.1524)
				(type default)
			)
			(layer "F.SilkS")
		)
		(fp_line
			(start -0.508 -0.9398)
			(end -0.508 0.9398)
			(stroke
				(width 0.1524)
				(type default)
			)
			(layer "F.SilkS")
		)
		(fp_rect
			(start -0.508 0.9398)
			(end 0.508 -0.9398)
			(stroke
				(width 0)
				(type default)
			)
			(fill no)
			(layer "F.CrtYd")
		)
		(fp_rect
			(start -0.508 0.9398)
			(end 0.508 -0.9398)
			(stroke
				(width 0)
				(type default)
			)
			(fill no)
			(layer "F.Fab")
		)
		(pad "1" smd custom
			(at 0 -0.4445 90)
			(size 0.1397 0.1397)
			(layers "F.Cu" "F.Mask" "F.Paste")
			(net "P3V3_STBY")
			(options
				(clearance outline)
				(anchor circle)
			)
			(primitives
				(gr_poly
					(pts
						(arc
							(start -0.1778 -0.2794)
							(mid -0.249642 -0.249642)
							(end -0.2794 -0.1778)
						)
						(arc
							(start -0.2794 0.1778)
							(mid -0.249642 0.249642)
							(end -0.1778 0.2794)
						)
						(arc
							(start 0.1778 0.2794)
							(mid 0.249642 0.249642)
							(end 0.2794 0.1778)
						)
						(arc
							(start 0.2794 -0.1778)
							(mid 0.249642 -0.249642)
							(end 0.1778 -0.2794)
						)
					)
					(width 0)
					(fill yes)
				)
			)
		)
		(pad "2" smd custom
			(at 0 0.4445 90)
			(size 0.1397 0.1397)
			(layers "F.Cu" "F.Mask" "F.Paste")
			(net "USB_OCS_N3")
			(options
				(clearance outline)
				(anchor circle)
			)
			(primitives
				(gr_poly
					(pts
						(arc
							(start -0.1778 -0.2794)
							(mid -0.249642 -0.249642)
							(end -0.2794 -0.1778)
						)
						(arc
							(start -0.2794 0.1778)
							(mid -0.249642 0.249642)
							(end -0.1778 0.2794)
						)
						(arc
							(start 0.1778 0.2794)
							(mid 0.249642 0.249642)
							(end 0.2794 0.1778)
						)
						(arc
							(start 0.2794 -0.1778)
							(mid 0.249642 -0.249642)
							(end 0.1778 -0.2794)
						)
					)
					(width 0)
					(fill yes)
				)
			)
		)
	)
	(footprint ""
		(layer "F.Cu")
		(at 341.122 -116.586 180)
		(property "Reference" "PC13"
			(at 0 0 180)
			(layer "F.SilkS")
			(hide yes)
			(effects
				(font
					(size 1.27 1.27)
				)
			)
		)
		(property "Value" "SC1U16V3KX-5GP"
			(at 0 -2.8194 180)
			(unlocked yes)
			(layer "F.Fab")
			(hide yes)
			(effects
				(font
					(size 1.016 1.016)
					(thickness 0.1524)
				)
			)
		)
		(property "Device Type" "C603H36"
			(at 0 -4.3434 180)
			(unlocked yes)
			(layer "F.Fab")
			(hide yes)
			(effects
				(font
					(size 1.016 1.016)
					(thickness 0.1524)
				)
			)
		)
		(duplicate_pad_numbers_are_jumpers no)
		(fp_line
			(start 0.508 0)
			(end -0.508 0)
			(stroke
				(width 0.2032)
				(type default)
			)
			(layer "F.SilkS")
		)
		(fp_rect
			(start -0.5842 1.3335)
			(end 0.5842 -1.3335)
			(stroke
				(width 0)
				(type default)
			)
			(fill no)
			(layer "F.CrtYd")
		)
		(fp_rect
			(start -0.5842 1.3335)
			(end 0.5842 -1.3335)
			(stroke
				(width 0)
				(type default)
			)
			(fill no)
			(layer "F.Fab")
		)
		(pad "1" smd custom
			(at 0 -0.762 180)
			(size 0.2159 0.2159)
			(layers "F.Cu" "F.Mask" "F.Paste")
			(net "P5V_STBY_VRG5")
			(options
				(clearance outline)
				(anchor circle)
			)
			(primitives
				(gr_poly
					(pts
						(arc
							(start -0.3302 -0.4318)
							(mid -0.402042 -0.402042)
							(end -0.4318 -0.3302)
						)
						(arc
							(start -0.4318 0.3302)
							(mid -0.402042 0.402042)
							(end -0.3302 0.4318)
						)
						(arc
							(start 0.3302 0.4318)
							(mid 0.402042 0.402042)
							(end 0.4318 0.3302)
						)
						(arc
							(start 0.4318 -0.3302)
							(mid 0.402042 -0.402042)
							(end 0.3302 -0.4318)
						)
					)
					(width 0)
					(fill yes)
				)
			)
		)
		(pad "2" smd custom
			(at 0 0.762 180)
			(size 0.2159 0.2159)
			(layers "F.Cu" "F.Mask" "F.Paste")
			(net "GND")
			(options
				(clearance outline)
				(anchor circle)
			)
			(primitives
				(gr_poly
					(pts
						(arc
							(start -0.3302 -0.4318)
							(mid -0.402042 -0.402042)
							(end -0.4318 -0.3302)
						)
						(arc
							(start -0.4318 0.3302)
							(mid -0.402042 0.402042)
							(end -0.3302 0.4318)
						)
						(arc
							(start 0.3302 0.4318)
							(mid 0.402042 0.402042)
							(end 0.4318 0.3302)
						)
						(arc
							(start 0.4318 -0.3302)
							(mid 0.402042 -0.402042)
							(end 0.3302 -0.4318)
						)
					)
					(width 0)
					(fill yes)
				)
			)
		)
	)
	(footprint ""
		(layer "F.Cu")
		(at 288.408872 -223.719136 180)
		(property "Reference" "PC86"
			(at 0 0 180)
			(layer "F.SilkS")
			(hide yes)
			(effects
				(font
					(size 1.27 1.27)
				)
			)
		)
		(property "Value" "SCD1U10V2KX-5GP"
			(at 1.1811 -2.7051 180)
			(unlocked yes)
			(layer "F.Fab")
			(hide yes)
			(effects
				(font
					(size 1.016 1.016)
					(thickness 0.1524)
				)
			)
		)
		(property "Device Type" "C402H22"
			(at 1.1811 -4.2291 180)
			(unlocked yes)
			(layer "F.Fab")
			(hide yes)
			(effects
				(font
					(size 1.016 1.016)
					(thickness 0.1524)
				)
			)
		)
		(duplicate_pad_numbers_are_jumpers no)
		(fp_rect
			(start -0.4318 0.9525)
			(end 0.4318 -0.9525)
			(stroke
				(width 0)
				(type default)
			)
			(fill no)
			(layer "F.CrtYd")
		)
		(fp_rect
			(start -0.4318 0.9525)
			(end 0.4318 -0.9525)
			(stroke
				(width 0)
				(type default)
			)
			(fill no)
			(layer "F.Fab")
		)
		(pad "1" smd custom
			(at 0 -0.4445 180)
			(size 0.1524 0.1524)
			(layers "F.Cu" "F.Mask" "F.Paste")
			(net "TPS74801_1V53_STBY_OUT")
			(options
				(clearance outline)
				(anchor circle)
			)
			(primitives
				(gr_poly
					(pts
						(arc
							(start 0.3048 -0.2032)
							(mid 0.275042 -0.275042)
							(end 0.2032 -0.3048)
						)
						(arc
							(start -0.2032 -0.3048)
							(mid -0.275042 -0.275042)
							(end -0.3048 -0.2032)
						)
						(arc
							(start -0.3048 0.2032)
							(mid -0.275042 0.275042)
							(end -0.2032 0.3048)
						)
						(arc
							(start 0.2032 0.3048)
							(mid 0.275042 0.275042)
							(end 0.3048 0.2032)
						)
					)
					(width 0)
					(fill yes)
				)
			)
		)
		(pad "2" smd custom
			(at 0 0.4445 180)
			(size 0.1524 0.1524)
			(layers "F.Cu" "F.Mask" "F.Paste")
			(net "GND")
			(options
				(clearance outline)
				(anchor circle)
			)
			(primitives
				(gr_poly
					(pts
						(arc
							(start 0.3048 -0.2032)
							(mid 0.275042 -0.275042)
							(end 0.2032 -0.3048)
						)
						(arc
							(start -0.2032 -0.3048)
							(mid -0.275042 -0.275042)
							(end -0.3048 -0.2032)
						)
						(arc
							(start -0.3048 0.2032)
							(mid -0.275042 0.275042)
							(end -0.2032 0.3048)
						)
						(arc
							(start 0.2032 0.3048)
							(mid 0.275042 0.275042)
							(end 0.3048 0.2032)
						)
					)
					(width 0)
					(fill yes)
				)
			)
		)
	)
	(footprint ""
		(layer "F.Cu")
		(at 222.123 -116.332 180)
		(property "Reference" "Q97"
			(at 0 0 180)
			(layer "F.SilkS")
			(hide yes)
			(effects
				(font
					(size 1.27 1.27)
				)
			)
		)
		(property "Value" "2N7002A-7-GP"
			(at 0.127 -8.9662 180)
			(unlocked yes)
			(layer "F.Fab")
			(hide yes)
			(effects
				(font
					(size 1.016 1.016)
					(thickness 0.1524)
				)
			)
		)
		(property "Device Type" "SOT23DGS2D4H48"
			(at 0.127 -10.4902 180)
			(unlocked yes)
			(layer "F.Fab")
			(hide yes)
			(effects
				(font
					(size 1.016 1.016)
					(thickness 0.1524)
				)
			)
		)
		(duplicate_pad_numbers_are_jumpers no)
		(fp_line
			(start 1.651 1.778)
			(end 1.651 -1.778)
			(stroke
				(width 0.1524)
				(type default)
			)
			(layer "F.SilkS")
		)
		(fp_line
			(start 1.651 -1.778)
			(end -1.651 -1.778)
			(stroke
				(width 0.1524)
				(type default)
			)
			(layer "F.SilkS")
		)
		(fp_line
			(start -1.651 1.778)
			(end 1.651 1.778)
			(stroke
				(width 0.1524)
				(type default)
			)
			(layer "F.SilkS")
		)
		(fp_line
			(start -1.651 -1.778)
			(end -1.651 1.778)
			(stroke
				(width 0.1524)
				(type default)
			)
			(layer "F.SilkS")
		)
		(fp_poly
			(pts
				(xy -1.778 1.8796) (xy -1.778 -1.8796) (xy 1.778 -1.8796) (xy 1.778 1.8796)
			)
			(stroke
				(width 0)
				(type default)
			)
			(fill no)
			(layer "F.CrtYd")
		)
		(fp_poly
			(pts
				(xy -1.778 1.8796) (xy -1.778 -1.8796) (xy 1.778 -1.8796) (xy 1.778 1.8796)
			)
			(stroke
				(width 0)
				(type default)
			)
			(fill no)
			(layer "F.Fab")
		)
		(pad "D" smd custom
			(at 0 -0.9525 180)
			(size 0.1905 0.1905)
			(layers "F.Cu" "F.Mask" "F.Paste")
			(net "P1V8_PG_R_2")
			(options
				(clearance outline)
				(anchor circle)
			)
			(primitives
				(gr_poly
					(pts
						(arc
							(start -0.1778 0.5715)
							(mid -0.321484 0.511984)
							(end -0.381 0.3683)
						)
						(arc
							(start -0.381 -0.3683)
							(mid -0.321484 -0.511984)
							(end -0.1778 -0.5715)
						)
						(arc
							(start 0.1778 -0.5715)
							(mid 0.321484 -0.511984)
							(end 0.381 -0.3683)
						)
						(arc
							(start 0.381 0.3683)
							(mid 0.321484 0.511984)
							(end 0.1778 0.5715)
						)
					)
					(width 0)
					(fill yes)
				)
			)
		)
		(pad "G" smd custom
			(at -0.98425 0.9525 180)
			(size 0.1905 0.1905)
			(layers "F.Cu" "F.Mask" "F.Paste")
			(net "P3V3_STBY_B3")
			(options
				(clearance outline)
				(anchor circle)
			)
			(primitives
				(gr_poly
					(pts
						(arc
							(start -0.1778 0.5715)
							(mid -0.321484 0.511984)
							(end -0.381 0.3683)
						)
						(arc
							(start -0.381 -0.3683)
							(mid -0.321484 -0.511984)
							(end -0.1778 -0.5715)
						)
						(arc
							(start 0.1778 -0.5715)
							(mid 0.321484 -0.511984)
							(end 0.381 -0.3683)
						)
						(arc
							(start 0.381 0.3683)
							(mid 0.321484 0.511984)
							(end 0.1778 0.5715)
						)
					)
					(width 0)
					(fill yes)
				)
			)
		)
		(pad "S" smd custom
			(at 0.98425 0.9525 180)
			(size 0.1905 0.1905)
			(layers "F.Cu" "F.Mask" "F.Paste")
			(net "GND")
			(options
				(clearance outline)
				(anchor circle)
			)
			(primitives
				(gr_poly
					(pts
						(arc
							(start -0.1778 0.5715)
							(mid -0.321484 0.511984)
							(end -0.381 0.3683)
						)
						(arc
							(start -0.381 -0.3683)
							(mid -0.321484 -0.511984)
							(end -0.1778 -0.5715)
						)
						(arc
							(start 0.1778 -0.5715)
							(mid 0.321484 -0.511984)
							(end 0.381 -0.3683)
						)
						(arc
							(start 0.381 0.3683)
							(mid 0.321484 0.511984)
							(end 0.1778 0.5715)
						)
					)
					(width 0)
					(fill yes)
				)
			)
		)
	)
)
